(kicad_pcb
	(version 20211014)
	(generator pcbnew)
	(general
    (thickness 1.6)
  )
	(paper "A4")
	(title_block
    (title "SA800U (Snapdragon 845) Baseboard")
    (date "2023-10-19")
    (rev "1.0.3")
    (company "Antmicro Ltd.")
    (comment 1 "www.antmicro.com")
		(comment 9 "footprints 128-136 of 589")
	)
	(layers
    (0 "F.Cu" signal)
    (1 "In1.Cu" power)
    (2 "In2.Cu" signal)
    (3 "In3.Cu" signal)
    (4 "In4.Cu" power)
    (31 "B.Cu" signal)
    (32 "B.Adhes" user "B.Adhesive")
    (33 "F.Adhes" user "F.Adhesive")
    (34 "B.Paste" user)
    (35 "F.Paste" user)
    (36 "B.SilkS" user "B.Silkscreen")
    (37 "F.SilkS" user "F.Silkscreen")
    (38 "B.Mask" user)
    (39 "F.Mask" user)
    (40 "Dwgs.User" user "User.Drawings")
    (41 "Cmts.User" user "User.Comments")
    (42 "Eco1.User" user "User.Eco1")
    (43 "Eco2.User" user "User.Eco2")
    (44 "Edge.Cuts" user)
    (45 "Margin" user)
    (46 "B.CrtYd" user "B.Courtyard")
    (47 "F.CrtYd" user "F.Courtyard")
    (48 "B.Fab" user)
    (49 "F.Fab" user)
  )
	(footprint "sa800u-baseboard-hw-footprints:XSON-8_1x1.95mm_P0.5mm" (layer "F.Cu")
    (tedit 5DCD5522)
    (at 113.8 107.7 -90)
    (property "Author" "Antmicro")
    (property "License" "Apache-2.0")
    (property "MPN" "NTS0102GT")
    (property "Manufacturer" "NXP")
    (property "Sheetfile" "other-interfaces.kicad_sch")
    (property "Sheetname" "Other Interfaces")
    (attr smd)
    (fp_text reference "U16" (at 0.99 1.4 90) (layer "F.SilkS")
      (effects (font (size 0.7 0.7) (thickness 0.15)) (justify left bottom))
    )
    (fp_text value "NTS0102_XSON" (at 0 2.2 -90) (layer "F.Fab")
      (effects (font (size 0.7 0.7) (thickness 0.15)) (justify left bottom))
    )
    (fp_text user "License: Apache-2.0" (at -0.527 8.306 -90) (layer "F.Fab") hide
      (effects (font (size 0.7 0.7) (thickness 0.15)) (justify left bottom))
    )
    (fp_text user "Author: Antmicro" (at -0.527 7.105 -90) (layer "F.Fab") hide
      (effects (font (size 0.7 0.7) (thickness 0.15)) (justify left bottom))
    )
    (fp_text user "${REFERENCE}" (at -0.527 5.905 -90) (layer "F.Fab") hide
      (effects (font (size 0.7 0.7) (thickness 0.15)) (justify left bottom))
    )
    (fp_line (start 0.5 1.1) (end -0.5 1.1) (layer "F.SilkS") (width 0.15))
    (fp_line (start -0.5 -1.1) (end 0.5 -1.1) (layer "F.SilkS") (width 0.15))
    (fp_circle (center -0.7 -0.95) (end -0.651 -0.95) (layer "F.SilkS") (width 0.15) (fill none))
    (fp_rect (start -0.8 -1.2) (end 0.8 1.2) (layer "F.CrtYd") (width 0.05) (fill none))
    (fp_line (start -0.5305 1) (end -0.5305 -1.001) (layer "F.Fab") (width 0.15))
    (fp_line (start 0.5305 1) (end -0.5305 1) (layer "F.Fab") (width 0.15))
    (fp_line (start 0.5305 -1.001) (end 0.5305 1) (layer "F.Fab") (width 0.15))
    (fp_line (start -0.5305 -1.001) (end 0.5305 -1.001) (layer "F.Fab") (width 0.15))
    (pad "1" smd rect (at -0.33 -0.75 270) (size 0.5 0.31) (layers "F.Cu" "F.Paste" "F.Mask")
      (net 338 "/Other Interfaces/I2C10_SDA_3V3") (pinfunction "B_{2}") (pintype "bidirectional"))
    (pad "2" smd rect (at -0.33 -0.25 270) (size 0.5 0.31) (layers "F.Cu" "F.Paste" "F.Mask")
      (net 1 "GND") (pinfunction "GND") (pintype "power_in"))
    (pad "3" smd rect (at -0.33 0.25 270) (size 0.5 0.31) (layers "F.Cu" "F.Paste" "F.Mask")
      (net 132 "VREG_S4A_1V8") (pinfunction "VCC_{A}") (pintype "power_in"))
    (pad "4" smd rect (at -0.33 0.75 270) (size 0.5 0.31) (layers "F.Cu" "F.Paste" "F.Mask")
      (net 151 "I2C10_SDA") (pinfunction "A_{2}") (pintype "bidirectional"))
    (pad "5" smd rect (at 0.33 0.75 90) (size 0.5 0.31) (layers "F.Cu" "F.Paste" "F.Mask")
      (net 150 "I2C10_SCL") (pinfunction "A_{1}") (pintype "bidirectional"))
    (pad "6" smd rect (at 0.33 0.25 90) (size 0.5 0.31) (layers "F.Cu" "F.Paste" "F.Mask")
      (net 132 "VREG_S4A_1V8") (pinfunction "OE") (pintype "input"))
    (pad "7" smd rect (at 0.33 -0.25 90) (size 0.5 0.31) (layers "F.Cu" "F.Paste" "F.Mask")
      (net 131 "3V3_SYS") (pinfunction "VCC_{B}") (pintype "power_in"))
    (pad "8" smd rect (at 0.33 -0.75 90) (size 0.5 0.31) (layers "F.Cu" "F.Paste" "F.Mask")
      (net 337 "/Other Interfaces/I2C10_SCL_3V3") (pinfunction "B_{1}") (pintype "bidirectional"))
  )
	(footprint "sa800u-baseboard-hw-footprints:R_0402_1005Metric" (layer "F.Cu")
    (tedit 5FD9C158)
    (at 122.8 106.8)
    (descr "Resistor SMD 0402")
    (tags "resistor SMD 0402")
    (property "Author" "Antmicro")
    (property "License" "Apache-2.0")
    (property "MPN" "CR0402-FX-2001GLF")
    (property "Manufacturer" "Bourns")
    (property "Sheetfile" "lcm.kicad_sch")
    (property "Sheetname" "LCM")
    (property "Tolerance" "1%")
    (property "Val" "2k")
    (attr smd)
    (fp_text reference "R68" (at 0.79 0.39) (layer "F.SilkS")
      (effects (font (size 0.7 0.7) (thickness 0.15)) (justify left bottom))
    )
    (fp_text value "R_2k_0402" (at 0 1.4) (layer "F.Fab")
      (effects (font (size 0.7 0.7) (thickness 0.15)) (justify left bottom))
    )
    (fp_text user "License: Apache-2.0" (at -0.95 5.169) (layer "F.Fab") hide
      (effects (font (size 0.7 0.7) (thickness 0.15)) (justify left bottom))
    )
    (fp_text user "Author: Antmicro" (at -0.95 4.169) (layer "F.Fab") hide
      (effects (font (size 0.7 0.7) (thickness 0.15)) (justify left bottom))
    )
    (fp_text user "${REFERENCE}" (at -0.95 3.168) (layer "F.Fab") hide
      (effects (font (size 0.7 0.7) (thickness 0.15)) (justify left bottom))
    )
    (fp_rect (start -0.93 -0.47) (end 0.93 0.47) (layer "F.CrtYd") (width 0.05) (fill none))
    (fp_rect (start -0.5 -0.25) (end 0.5 0.25) (layer "F.Fab") (width 0.15) (fill none))
    (pad "1" smd roundrect (at -0.485 0) (size 0.59 0.64) (layers "F.Cu" "F.Paste" "F.Mask") (roundrect_rratio 0.25)
      (net 149 "/LCM/TP_I2C_SDA_3V3") (pintype "passive"))
    (pad "2" smd roundrect (at 0.485 0) (size 0.59 0.64) (layers "F.Cu" "F.Paste" "F.Mask") (roundrect_rratio 0.25)
      (net 131 "3V3_SYS") (pintype "passive"))
  )
	(footprint "sa800u-baseboard-hw-footprints:R_0402_1005Metric" (layer "F.Cu")
    (tedit 5FD9C158)
    (at 113.3 96.75 -90)
    (descr "Resistor SMD 0402")
    (tags "resistor SMD 0402")
    (property "Author" "Antmicro")
    (property "License" "Apache-2.0")
    (property "MPN" "CR0402-FX-2001GLF")
    (property "Manufacturer" "Bourns")
    (property "Sheetfile" "camera-interface.kicad_sch")
    (property "Sheetname" "Camera Interface")
    (property "Tolerance" "1%")
    (property "Val" "2k")
    (attr smd)
    (fp_text reference "R80" (at 3.05 -0.35 -90) (layer "F.SilkS")
      (effects (font (size 0.7 0.7) (thickness 0.15)) (justify left bottom))
    )
    (fp_text value "R_2k_0402" (at 0 1.4 -90) (layer "F.Fab")
      (effects (font (size 0.7 0.7) (thickness 0.15)) (justify left bottom))
    )
    (fp_text user "License: Apache-2.0" (at -0.95 5.169 -90) (layer "F.Fab") hide
      (effects (font (size 0.7 0.7) (thickness 0.15)) (justify left bottom))
    )
    (fp_text user "${REFERENCE}" (at -0.95 3.168 -90) (layer "F.Fab") hide
      (effects (font (size 0.7 0.7) (thickness 0.15)) (justify left bottom))
    )
    (fp_text user "Author: Antmicro" (at -0.95 4.169 -90) (layer "F.Fab") hide
      (effects (font (size 0.7 0.7) (thickness 0.15)) (justify left bottom))
    )
    (fp_rect (start -0.93 -0.47) (end 0.93 0.47) (layer "F.CrtYd") (width 0.05) (fill none))
    (fp_rect (start -0.5 -0.25) (end 0.5 0.25) (layer "F.Fab") (width 0.15) (fill none))
    (pad "1" smd roundrect (at -0.485 0 270) (size 0.59 0.64) (layers "F.Cu" "F.Paste" "F.Mask") (roundrect_rratio 0.25)
      (net 45 "CCI1_I2C_SDA") (pintype "passive"))
    (pad "2" smd roundrect (at 0.485 0 270) (size 0.59 0.64) (layers "F.Cu" "F.Paste" "F.Mask") (roundrect_rratio 0.25)
      (net 139 "LVS1A_1V8") (pintype "passive"))
  )
	(footprint "sa800u-baseboard-hw-footprints:R_0402_1005Metric" (layer "F.Cu")
    (tedit 5FD9C158)
    (at 109.8 96.75 -90)
    (descr "Resistor SMD 0402")
    (tags "resistor SMD 0402")
    (property "Author" "Antmicro")
    (property "License" "Apache-2.0")
    (property "MPN" "CR0402-FX-2001GLF")
    (property "Manufacturer" "Bourns")
    (property "Sheetfile" "camera-interface.kicad_sch")
    (property "Sheetname" "Camera Interface")
    (property "Tolerance" "1%")
    (property "Val" "2k")
    (attr smd)
    (fp_text reference "R81" (at 3.05 -0.36 -90) (layer "F.SilkS")
      (effects (font (size 0.7 0.7) (thickness 0.15)) (justify left bottom))
    )
    (fp_text value "R_2k_0402" (at 0 1.4 -90) (layer "F.Fab")
      (effects (font (size 0.7 0.7) (thickness 0.15)) (justify left bottom))
    )
    (fp_text user "License: Apache-2.0" (at -0.95 5.169 -90) (layer "F.Fab") hide
      (effects (font (size 0.7 0.7) (thickness 0.15)) (justify left bottom))
    )
    (fp_text user "Author: Antmicro" (at -0.95 4.169 -90) (layer "F.Fab") hide
      (effects (font (size 0.7 0.7) (thickness 0.15)) (justify left bottom))
    )
    (fp_text user "${REFERENCE}" (at -0.95 3.168 -90) (layer "F.Fab") hide
      (effects (font (size 0.7 0.7) (thickness 0.15)) (justify left bottom))
    )
    (fp_rect (start -0.93 -0.47) (end 0.93 0.47) (layer "F.CrtYd") (width 0.05) (fill none))
    (fp_rect (start -0.5 -0.25) (end 0.5 0.25) (layer "F.Fab") (width 0.15) (fill none))
    (pad "1" smd roundrect (at -0.485 0 270) (size 0.59 0.64) (layers "F.Cu" "F.Paste" "F.Mask") (roundrect_rratio 0.25)
      (net 43 "CCI0_I2C_SDA") (pintype "passive"))
    (pad "2" smd roundrect (at 0.485 0 270) (size 0.59 0.64) (layers "F.Cu" "F.Paste" "F.Mask") (roundrect_rratio 0.25)
      (net 139 "LVS1A_1V8") (pintype "passive"))
  )
	(footprint "sa800u-baseboard-hw-footprints:R_0402_1005Metric" (layer "F.Cu")
    (tedit 5FD9C158)
    (at 114.3 96.75 -90)
    (descr "Resistor SMD 0402")
    (tags "resistor SMD 0402")
    (property "Author" "Antmicro")
    (property "License" "Apache-2.0")
    (property "MPN" "CR0402-FX-2001GLF")
    (property "Manufacturer" "Bourns")
    (property "Sheetfile" "camera-interface.kicad_sch")
    (property "Sheetname" "Camera Interface")
    (property "Tolerance" "1%")
    (property "Val" "2k")
    (attr smd)
    (fp_text reference "R82" (at 3.05 -0.35 -90) (layer "F.SilkS")
      (effects (font (size 0.7 0.7) (thickness 0.15)) (justify left bottom))
    )
    (fp_text value "R_2k_0402" (at 0 1.4 -90) (layer "F.Fab")
      (effects (font (size 0.7 0.7) (thickness 0.15)) (justify left bottom))
    )
    (fp_text user "Author: Antmicro" (at -0.95 4.169 -90) (layer "F.Fab") hide
      (effects (font (size 0.7 0.7) (thickness 0.15)) (justify left bottom))
    )
    (fp_text user "${REFERENCE}" (at -0.95 3.168 -90) (layer "F.Fab") hide
      (effects (font (size 0.7 0.7) (thickness 0.15)) (justify left bottom))
    )
    (fp_text user "License: Apache-2.0" (at -0.95 5.169 -90) (layer "F.Fab") hide
      (effects (font (size 0.7 0.7) (thickness 0.15)) (justify left bottom))
    )
    (fp_rect (start -0.93 -0.47) (end 0.93 0.47) (layer "F.CrtYd") (width 0.05) (fill none))
    (fp_rect (start -0.5 -0.25) (end 0.5 0.25) (layer "F.Fab") (width 0.15) (fill none))
    (pad "1" smd roundrect (at -0.485 0 270) (size 0.59 0.64) (layers "F.Cu" "F.Paste" "F.Mask") (roundrect_rratio 0.25)
      (net 44 "CCI1_I2C_SCL") (pintype "passive"))
    (pad "2" smd roundrect (at 0.485 0 270) (size 0.59 0.64) (layers "F.Cu" "F.Paste" "F.Mask") (roundrect_rratio 0.25)
      (net 139 "LVS1A_1V8") (pintype "passive"))
  )
	(footprint "sa800u-baseboard-hw-footprints:R_0402_1005Metric" (layer "F.Cu")
    (tedit 5FD9C158)
    (at 110.8 96.75 -90)
    (descr "Resistor SMD 0402")
    (tags "resistor SMD 0402")
    (property "Author" "Antmicro")
    (property "License" "Apache-2.0")
    (property "MPN" "CR0402-FX-2001GLF")
    (property "Manufacturer" "Bourns")
    (property "Sheetfile" "camera-interface.kicad_sch")
    (property "Sheetname" "Camera Interface")
    (property "Tolerance" "1%")
    (property "Val" "2k")
    (attr smd)
    (fp_text reference "R83" (at 3.05 -0.36 -90) (layer "F.SilkS")
      (effects (font (size 0.7 0.7) (thickness 0.15)) (justify left bottom))
    )
    (fp_text value "R_2k_0402" (at 0 1.4 -90) (layer "F.Fab")
      (effects (font (size 0.7 0.7) (thickness 0.15)) (justify left bottom))
    )
    (fp_text user "${REFERENCE}" (at -0.95 3.168 -90) (layer "F.Fab") hide
      (effects (font (size 0.7 0.7) (thickness 0.15)) (justify left bottom))
    )
    (fp_text user "Author: Antmicro" (at -0.95 4.169 -90) (layer "F.Fab") hide
      (effects (font (size 0.7 0.7) (thickness 0.15)) (justify left bottom))
    )
    (fp_text user "License: Apache-2.0" (at -0.95 5.169 -90) (layer "F.Fab") hide
      (effects (font (size 0.7 0.7) (thickness 0.15)) (justify left bottom))
    )
    (fp_rect (start -0.93 -0.47) (end 0.93 0.47) (layer "F.CrtYd") (width 0.05) (fill none))
    (fp_rect (start -0.5 -0.25) (end 0.5 0.25) (layer "F.Fab") (width 0.15) (fill none))
    (pad "1" smd roundrect (at -0.485 0 270) (size 0.59 0.64) (layers "F.Cu" "F.Paste" "F.Mask") (roundrect_rratio 0.25)
      (net 42 "CCI0_I2C_SCL") (pintype "passive"))
    (pad "2" smd roundrect (at 0.485 0 270) (size 0.59 0.64) (layers "F.Cu" "F.Paste" "F.Mask") (roundrect_rratio 0.25)
      (net 139 "LVS1A_1V8") (pintype "passive"))
  )
	(footprint "sa800u-baseboard-hw-footprints:XSON-8_1x1.95mm_P0.5mm" (layer "F.Cu")
    (tedit 5DCD5522)
    (at 120.895 108.6)
    (property "Author" "Antmicro")
    (property "License" "Apache-2.0")
    (property "MPN" "NTS0102GT")
    (property "Manufacturer" "NXP")
    (property "Sheetfile" "lcm.kicad_sch")
    (property "Sheetname" "LCM")
    (attr smd)
    (fp_text reference "U10" (at -1.125 -1.29) (layer "F.SilkS")
      (effects (font (size 0.7 0.7) (thickness 0.15)) (justify left bottom))
    )
    (fp_text value "NTS0102_XSON" (at 0 2.2) (layer "F.Fab")
      (effects (font (size 0.7 0.7) (thickness 0.15)) (justify left bottom))
    )
    (fp_text user "License: Apache-2.0" (at -0.527 8.306) (layer "F.Fab") hide
      (effects (font (size 0.7 0.7) (thickness 0.15)) (justify left bottom))
    )
    (fp_text user "${REFERENCE}" (at -0.527 5.905) (layer "F.Fab") hide
      (effects (font (size 0.7 0.7) (thickness 0.15)) (justify left bottom))
    )
    (fp_text user "Author: Antmicro" (at -0.527 7.105) (layer "F.Fab") hide
      (effects (font (size 0.7 0.7) (thickness 0.15)) (justify left bottom))
    )
    (fp_line (start 0.5 1.1) (end -0.5 1.1) (layer "F.SilkS") (width 0.15))
    (fp_line (start -0.5 -1.1) (end 0.5 -1.1) (layer "F.SilkS") (width 0.15))
    (fp_circle (center -0.7 -0.95) (end -0.651 -0.95) (layer "F.SilkS") (width 0.15) (fill none))
    (fp_rect (start -0.8 -1.2) (end 0.8 1.2) (layer "F.CrtYd") (width 0.05) (fill none))
    (fp_line (start -0.5305 1) (end -0.5305 -1.001) (layer "F.Fab") (width 0.15))
    (fp_line (start -0.5305 -1.001) (end 0.5305 -1.001) (layer "F.Fab") (width 0.15))
    (fp_line (start 0.5305 -1.001) (end 0.5305 1) (layer "F.Fab") (width 0.15))
    (fp_line (start 0.5305 1) (end -0.5305 1) (layer "F.Fab") (width 0.15))
    (pad "1" smd rect (at -0.33 -0.75) (size 0.5 0.31) (layers "F.Cu" "F.Paste" "F.Mask")
      (net 149 "/LCM/TP_I2C_SDA_3V3") (pinfunction "B_{2}") (pintype "bidirectional"))
    (pad "2" smd rect (at -0.33 -0.25) (size 0.5 0.31) (layers "F.Cu" "F.Paste" "F.Mask")
      (net 1 "GND") (pinfunction "GND") (pintype "power_in"))
    (pad "3" smd rect (at -0.33 0.25) (size 0.5 0.31) (layers "F.Cu" "F.Paste" "F.Mask")
      (net 139 "LVS1A_1V8") (pinfunction "VCC_{A}") (pintype "power_in"))
    (pad "4" smd rect (at -0.33 0.75) (size 0.5 0.31) (layers "F.Cu" "F.Paste" "F.Mask")
      (net 82 "TP_I2C_SDA") (pinfunction "A_{2}") (pintype "bidirectional"))
    (pad "5" smd rect (at 0.33 0.75 180) (size 0.5 0.31) (layers "F.Cu" "F.Paste" "F.Mask")
      (net 81 "TP_I2C_SCL") (pinfunction "A_{1}") (pintype "bidirectional"))
    (pad "6" smd rect (at 0.33 0.25 180) (size 0.5 0.31) (layers "F.Cu" "F.Paste" "F.Mask")
      (net 139 "LVS1A_1V8") (pinfunction "OE") (pintype "input"))
    (pad "7" smd rect (at 0.33 -0.25 180) (size 0.5 0.31) (layers "F.Cu" "F.Paste" "F.Mask")
      (net 131 "3V3_SYS") (pinfunction "VCC_{B}") (pintype "power_in"))
    (pad "8" smd rect (at 0.33 -0.75 180) (size 0.5 0.31) (layers "F.Cu" "F.Paste" "F.Mask")
      (net 148 "/LCM/TP_I2C_SCL_3V3") (pinfunction "B_{1}") (pintype "bidirectional"))
  )
	(footprint "sa800u-baseboard-hw-footprints:R_0402_1005Metric" (layer "F.Cu")
    (tedit 5FD9C158)
    (at 115 120.3)
    (descr "Resistor SMD 0402")
    (tags "resistor SMD 0402")
    (property "Author" "Antmicro")
    (property "License" "Apache-2.0")
    (property "MPN" "CR0402-FX-4701GLF")
    (property "Manufacturer" "Bourns")
    (property "Sheetfile" "som.kicad_sch")
    (property "Sheetname" "SoM")
    (property "Tolerance" "1%")
    (property "Val" "4k7")
    (attr smd)
    (fp_text reference "R72" (at 0.94 0.34) (layer "F.SilkS")
      (effects (font (size 0.7 0.7) (thickness 0.15)) (justify left bottom))
    )
    (fp_text value "R_4k7_0402" (at 0 1.4) (layer "F.Fab")
      (effects (font (size 0.7 0.7) (thickness 0.15)) (justify left bottom))
    )
    (fp_text user "${REFERENCE}" (at -0.95 3.168) (layer "F.Fab") hide
      (effects (font (size 0.7 0.7) (thickness 0.15)) (justify left bottom))
    )
    (fp_text user "License: Apache-2.0" (at -0.95 5.169) (layer "F.Fab") hide
      (effects (font (size 0.7 0.7) (thickness 0.15)) (justify left bottom))
    )
    (fp_text user "Author: Antmicro" (at -0.95 4.169) (layer "F.Fab") hide
      (effects (font (size 0.7 0.7) (thickness 0.15)) (justify left bottom))
    )
    (fp_rect (start -0.93 -0.47) (end 0.93 0.47) (layer "F.CrtYd") (width 0.05) (fill none))
    (fp_rect (start -0.5 -0.25) (end 0.5 0.25) (layer "F.Fab") (width 0.15) (fill none))
    (pad "1" smd roundrect (at -0.485 0) (size 0.59 0.64) (layers "F.Cu" "F.Paste" "F.Mask") (roundrect_rratio 0.25)
      (net 150 "I2C10_SCL") (pintype "passive"))
    (pad "2" smd roundrect (at 0.485 0) (size 0.59 0.64) (layers "F.Cu" "F.Paste" "F.Mask") (roundrect_rratio 0.25)
      (net 132 "VREG_S4A_1V8") (pintype "passive"))
  )
	(footprint "sa800u-baseboard-hw-footprints:R_0402_1005Metric" (layer "F.Cu")
    (tedit 5FD9C158)
    (at 115 121.3)
    (descr "Resistor SMD 0402")
    (tags "resistor SMD 0402")
    (property "Author" "Antmicro")
    (property "License" "Apache-2.0")
    (property "MPN" "CR0402-FX-4701GLF")
    (property "Manufacturer" "Bourns")
    (property "Sheetfile" "som.kicad_sch")
    (property "Sheetname" "SoM")
    (property "Tolerance" "1%")
    (property "Val" "4k7")
    (attr smd)
    (fp_text reference "R71" (at 0.94 0.34) (layer "F.SilkS")
      (effects (font (size 0.7 0.7) (thickness 0.15)) (justify left bottom))
    )
    (fp_text value "R_4k7_0402" (at 0 1.4) (layer "F.Fab")
      (effects (font (size 0.7 0.7) (thickness 0.15)) (justify left bottom))
    )
    (fp_text user "${REFERENCE}" (at -0.95 3.168) (layer "F.Fab") hide
      (effects (font (size 0.7 0.7) (thickness 0.15)) (justify left bottom))
    )
    (fp_text user "License: Apache-2.0" (at -0.95 5.169) (layer "F.Fab") hide
      (effects (font (size 0.7 0.7) (thickness 0.15)) (justify left bottom))
    )
    (fp_text user "Author: Antmicro" (at -0.95 4.169) (layer "F.Fab") hide
      (effects (font (size 0.7 0.7) (thickness 0.15)) (justify left bottom))
    )
    (fp_rect (start -0.93 -0.47) (end 0.93 0.47) (layer "F.CrtYd") (width 0.05) (fill none))
    (fp_rect (start -0.5 -0.25) (end 0.5 0.25) (layer "F.Fab") (width 0.15) (fill none))
    (pad "1" smd roundrect (at -0.485 0) (size 0.59 0.64) (layers "F.Cu" "F.Paste" "F.Mask") (roundrect_rratio 0.25)
      (net 151 "I2C10_SDA") (pintype "passive"))
    (pad "2" smd roundrect (at 0.485 0) (size 0.59 0.64) (layers "F.Cu" "F.Paste" "F.Mask") (roundrect_rratio 0.25)
      (net 132 "VREG_S4A_1V8") (pintype "passive"))
  )
)
